# S9S_MB_2U (Grand Teton) — schematic netlist excerpt (pin names and nets, part order shuffled) for the footprints in the layout excerpt that follows; sources: Cadence DE-HDL packaged netlist, KiCad conversion of 03242023_DA0F0TMBIJ0_F0T_Motherboard_J_brd_V01_OCP.brd

PR3945  Q_RES  71.5K 1% EMPTY  pkg 0402LF  page 193 : A = P3V3_E1S_MODE_0 ; B = GND
C827  Q_CAP_DIFFBUS  DIFF BUS_0.22UF 6.3V 20% X6S  pkg C0201  page 175 : \1\ = P5E_CPU1_PE1_TX_C_DP<5> ; \2\ = P5E_CPU1_PE1_TX_DP<5>

Q56  MOSFET_NCH_1D3S  PSMNR58-30YLH IC  pkg SOT1023  page 260
  \1\  = P3V3
  \2\  = P3V3
  \3\  = P3V3
  \4\  = PWRGD_P5V_ISO_R
  \5\  = P3V3_AUX

(kicad_pcb
	(version 20260206)
	(generator "pcbnew")
	(generator_version "10.0")
	(general
		(thickness 1.6)
		(legacy_teardrops no)
	)
	(paper "A4")
	(title_block
		(title "03242023_DA0F0TMBIJ0_F0T_Motherboard_J_brd_V01_OCP.brd")
		(comment 1 "Grand Teton / footprints 1475-1477 of 6105")
	)
	(layers
		(0 "F.Cu" signal "TOP")
		(4 "In1.Cu" signal "GND")
		(6 "In2.Cu" signal "IN1")
		(8 "In3.Cu" signal "GND1")
		(10 "In4.Cu" signal "IN2")
		(12 "In5.Cu" signal "GND2")
		(14 "In6.Cu" signal "IN3")
		(16 "In7.Cu" signal "GND3")
		(18 "In8.Cu" signal "VCC")
		(20 "In9.Cu" signal "VCC1")
		(22 "In10.Cu" signal "GND4")
		(24 "In11.Cu" signal "IN4")
		(26 "In12.Cu" signal "GND5")
		(28 "In13.Cu" signal "IN5")
		(30 "In14.Cu" signal "GND6")
		(32 "In15.Cu" signal "IN6")
		(34 "In16.Cu" signal "GND7")
		(2 "B.Cu" signal "BOTTOM")
		(9 "F.Adhes" user "F.Adhesive")
		(11 "B.Adhes" user "B.Adhesive")
		(13 "F.Paste" user "Package Geometry/Pastemask Top")
		(15 "B.Paste" user "Package Geometry/Pastemask Bottom")
		(5 "F.SilkS" user "Ref Des/Silkscreen Top")
		(7 "B.SilkS" user "Ref Des/Silkscreen Bottom")
		(1 "F.Mask" user "Board Geometry/Soldermask Top")
		(3 "B.Mask" user "Board Geometry/Soldermask Bottom")
		(17 "Dwgs.User" user "User.Drawings")
		(19 "Cmts.User" user "User.Comments")
		(21 "Eco1.User" user "User.Eco1")
		(23 "Eco2.User" user "User.Eco2")
		(25 "Edge.Cuts" user "Board Geometry/Outline")
		(27 "Margin" user)
		(31 "F.CrtYd" user "Package Geometry/Place Bound Top")
		(29 "B.CrtYd" user "Package Geometry/Place Bound Bottom")
		(35 "F.Fab" user "Ref Des/Assembly Top")
		(33 "B.Fab" user "Ref Des/Assembly Bottom")
	)
	(footprint ""
		(layer "F.Cu")
		(at 437.58358 -55.26532)
		(property "Reference" "Q56"
			(at -0.813308 3.743452 0)
			(unlocked yes)
			(layer "F.SilkS")
			(effects
				(font
					(size 0.7874 0.5842)
					(thickness 0.1524)
				)
			)
		)
		(property "Value" ""
			(at 0 0 0)
			(layer "F.Fab")
			(effects
				(font
					(size 1.27 1.27)
				)
			)
		)
		(duplicate_pad_numbers_are_jumpers no)
		(fp_line
			(start -2.350008 -2.649982)
			(end 2.350008 -2.649982)
			(stroke
				(width 0.1524)
				(type default)
			)
			(layer "F.SilkS")
		)
		(fp_line
			(start -2.350008 -2.4384)
			(end -2.350008 -2.649982)
			(stroke
				(width 0.1524)
				(type default)
			)
			(layer "F.SilkS")
		)
		(fp_line
			(start -2.350008 2.649982)
			(end -2.350008 2.413)
			(stroke
				(width 0.1524)
				(type default)
			)
			(layer "F.SilkS")
		)
		(fp_line
			(start 2.350008 -2.649982)
			(end 2.350008 -2.4892)
			(stroke
				(width 0.1524)
				(type default)
			)
			(layer "F.SilkS")
		)
		(fp_line
			(start 2.350008 2.4892)
			(end 2.350008 2.649982)
			(stroke
				(width 0.1524)
				(type default)
			)
			(layer "F.SilkS")
		)
		(fp_line
			(start 2.350008 2.649982)
			(end -2.350008 2.649982)
			(stroke
				(width 0.1524)
				(type default)
			)
			(layer "F.SilkS")
		)
		(fp_poly
			(pts
				(xy -3.00609 -2.66827) (xy -3.38709 -3.70967) (xy -2.58699 -3.70967)
			)
			(stroke
				(width 0)
				(type default)
			)
			(fill yes)
			(layer "F.SilkS")
		)
		(fp_line
			(start -2.350008 -2.649982)
			(end 2.350008 -2.649982)
			(stroke
				(width 0.1)
				(type default)
			)
			(layer "F.Fab")
		)
		(fp_line
			(start -2.350008 2.649982)
			(end -2.350008 -2.649982)
			(stroke
				(width 0.1)
				(type default)
			)
			(layer "F.Fab")
		)
		(fp_line
			(start 2.350008 -2.649982)
			(end 2.350008 2.649982)
			(stroke
				(width 0.1)
				(type default)
			)
			(layer "F.Fab")
		)
		(fp_line
			(start 2.350008 2.649982)
			(end -2.350008 2.649982)
			(stroke
				(width 0.1)
				(type default)
			)
			(layer "F.Fab")
		)
		(fp_poly
			(pts
				(xy -3.717544 -1.905) (xy -4.758944 -2.3241) (xy -4.758944 -1.524)
			)
			(stroke
				(width 0)
				(type default)
			)
			(fill yes)
			(layer "F.Fab")
		)
		(pad "1" smd rect
			(at -2.999994 -1.905 270)
			(size 0.7112 1.1684)
			(layers "F.Cu" "F.Mask" "F.Paste")
			(net "P3V3")
		)
		(pad "2" smd rect
			(at -2.999994 -0.635 270)
			(size 0.7112 1.1684)
			(layers "F.Cu" "F.Mask" "F.Paste")
			(net "P3V3")
		)
		(pad "3" smd rect
			(at -2.999994 0.635 270)
			(size 0.7112 1.1684)
			(layers "F.Cu" "F.Mask" "F.Paste")
			(net "P3V3")
		)
		(pad "4" smd rect
			(at -2.999994 1.905 270)
			(size 0.7112 1.1684)
			(layers "F.Cu" "F.Mask" "F.Paste")
			(net "PWRGD_P5V_ISO_R")
		)
		(pad "5" smd circle
			(at 0.925068 0 270)
			(size 0 0)
			(layers "F.Cu" "F.Mask" "F.Paste")
			(net "P3V3_AUX")
		)
		(zone
			(layer "F.Cu")
			(hatch none 0.5)
			(connect_pads
				(clearance 0)
			)
			(min_thickness 0.25)
			(keepout
				(tracks not_allowed)
				(vias allowed)
				(pads allowed)
				(copperpour not_allowed)
				(footprints allowed)
			)
			(placement
				(enabled no)
				(sheetname "")
			)
			(fill
				(thermal_gap 0.5)
				(thermal_bridge_width 0.5)
				(island_removal_mode 0)
			)
			(polygon
				(pts
					(xy 436.13578 -57.42432) (xy 436.13578 -53.10632) (xy 436.13578 -52.62372) (xy 435.23408 -52.62372)
					(xy 435.23408 -57.90692) (xy 435.873652 -57.90692) (xy 436.13578 -57.644792)
				)
			)
		)
	)
	(footprint ""
		(layer "F.Cu")
		(at 190.41364 -67.391788 180)
		(property "Reference" "PR3945"
			(at 0 0 180)
			(layer "F.SilkS")
			(hide yes)
			(effects
				(font
					(size 1.27 1.27)
				)
			)
		)
		(property "Value" ""
			(at 0 0 180)
			(layer "F.Fab")
			(effects
				(font
					(size 1.27 1.27)
				)
			)
		)
		(duplicate_pad_numbers_are_jumpers no)
		(fp_line
			(start 0.7874 0.4064)
			(end -0.7874 0.4064)
			(stroke
				(width 0.1524)
				(type default)
			)
			(layer "F.SilkS")
		)
		(fp_line
			(start 0.7874 -0.4064)
			(end 0.7874 0.4064)
			(stroke
				(width 0.1524)
				(type default)
			)
			(layer "F.SilkS")
		)
		(fp_line
			(start -0.7874 0.4064)
			(end -0.7874 -0.4064)
			(stroke
				(width 0.1524)
				(type default)
			)
			(layer "F.SilkS")
		)
		(fp_line
			(start -0.7874 -0.4064)
			(end 0.7874 -0.4064)
			(stroke
				(width 0.1524)
				(type default)
			)
			(layer "F.SilkS")
		)
		(fp_line
			(start 0.67945 0.3048)
			(end 0.120396 0.3048)
			(stroke
				(width 0.1)
				(type default)
			)
			(layer "F.Fab")
		)
		(fp_line
			(start 0.67945 -0.3048)
			(end 0.67945 0.3048)
			(stroke
				(width 0.1)
				(type default)
			)
			(layer "F.Fab")
		)
		(fp_line
			(start 0.12065 -0.2794)
			(end 0.12065 -0.3048)
			(stroke
				(width 0.1)
				(type default)
			)
			(layer "F.Fab")
		)
		(fp_line
			(start 0.12065 -0.3048)
			(end 0.67945 -0.3048)
			(stroke
				(width 0.1)
				(type default)
			)
			(layer "F.Fab")
		)
		(fp_line
			(start 0.120396 0.3048)
			(end 0.120396 0.2794)
			(stroke
				(width 0.1)
				(type default)
			)
			(layer "F.Fab")
		)
		(fp_line
			(start 0.120396 0.2794)
			(end -0.12065 0.2794)
			(stroke
				(width 0.1)
				(type default)
			)
			(layer "F.Fab")
		)
		(fp_line
			(start -0.12065 0.3048)
			(end -0.67945 0.3048)
			(stroke
				(width 0.1)
				(type default)
			)
			(layer "F.Fab")
		)
		(fp_line
			(start -0.12065 0.2794)
			(end -0.12065 0.3048)
			(stroke
				(width 0.1)
				(type default)
			)
			(layer "F.Fab")
		)
		(fp_line
			(start -0.12065 -0.2794)
			(end 0.12065 -0.2794)
			(stroke
				(width 0.1)
				(type default)
			)
			(layer "F.Fab")
		)
		(fp_line
			(start -0.12065 -0.305054)
			(end -0.12065 -0.2794)
			(stroke
				(width 0.1)
				(type default)
			)
			(layer "F.Fab")
		)
		(fp_line
			(start -0.67945 0.3048)
			(end -0.67945 -0.305054)
			(stroke
				(width 0.1)
				(type default)
			)
			(layer "F.Fab")
		)
		(fp_line
			(start -0.67945 -0.305054)
			(end -0.12065 -0.305054)
			(stroke
				(width 0.1)
				(type default)
			)
			(layer "F.Fab")
		)
		(pad "1" smd circle
			(at -0.40005 0 180)
			(size 0 0)
			(layers "F.Cu" "F.Mask" "F.Paste")
			(net "P3V3_E1S_MODE_0")
		)
		(pad "2" smd circle
			(at 0.40005 0 180)
			(size 0 0)
			(layers "F.Cu" "F.Mask" "F.Paste")
			(net "GND")
		)
	)
	(footprint ""
		(layer "F.Cu")
		(at 43.754294 -16.099536 90)
		(property "Reference" "C827"
			(at 0 0 90)
			(layer "F.SilkS")
			(hide yes)
			(effects
				(font
					(size 1.27 1.27)
				)
			)
		)
		(property "Value" ""
			(at 0 0 90)
			(layer "F.Fab")
			(effects
				(font
					(size 1.27 1.27)
				)
			)
		)
		(duplicate_pad_numbers_are_jumpers no)
		(fp_line
			(start 0.299974 -0.150114)
			(end 0.299974 0.150114)
			(stroke
				(width 0.1)
				(type default)
			)
			(layer "F.Fab")
		)
		(fp_line
			(start -0.299974 -0.150114)
			(end 0.299974 -0.150114)
			(stroke
				(width 0.1)
				(type default)
			)
			(layer "F.Fab")
		)
		(fp_line
			(start 0.299974 0.150114)
			(end -0.299974 0.150114)
			(stroke
				(width 0.1)
				(type default)
			)
			(layer "F.Fab")
		)
		(fp_line
			(start -0.299974 0.150114)
			(end -0.299974 -0.150114)
			(stroke
				(width 0.1)
				(type default)
			)
			(layer "F.Fab")
		)
		(pad "1" smd rect
			(at -0.2667 0 90)
			(size 0.3048 0.381)
			(layers "F.Cu" "F.Mask" "F.Paste")
			(net "P5E_CPU1_PE1_TX_C_DP<5>")
		)
		(pad "2" smd rect
			(at 0.2667 0 90)
			(size 0.3048 0.381)
			(layers "F.Cu" "F.Mask" "F.Paste")
			(net "P5E_CPU1_PE1_TX_DP<5>")
		)
	)
)
